# T6G (Grand Teton) — schematic netlist excerpt (pin names and nets, part order shuffled) for the footprints in the layout excerpt that follows; sources: Cadence DE-HDL packaged netlist, KiCad conversion of 04192023_DAF0TMB3IC0_F0TG_MB_C_brd_V02_OCP.brd

R3200  Q_RES  0 5% CHIP  pkg 0402LF  page 55 : A = CLK_100M_CPU1_CLK05_R_DP ; B = CLK_100M_CPU1_CLK05_DP
R3231  Q_RES  33.2 1% CHIP  pkg 0402LF  page 132 : A = OCP_SFF_AUX_PWR_EN ; B = OCP_SFF_AUX_PWR_EN_R2

(kicad_pcb
	(version 20260206)
	(generator "pcbnew")
	(generator_version "10.0")
	(general
		(thickness 1.6)
		(legacy_teardrops no)
	)
	(paper "A4")
	(title_block
		(title "04192023_DAF0TMB3IC0_F0TG_MB_C_brd_V02_OCP.brd")
		(comment 1 "Grand Teton / footprints 2772-2773 of 8354")
	)
	(layers
		(0 "F.Cu" signal "TOP")
		(4 "In1.Cu" signal "GND")
		(6 "In2.Cu" signal "IN1")
		(8 "In3.Cu" signal "GND1")
		(10 "In4.Cu" signal "IN2")
		(12 "In5.Cu" signal "GND2")
		(14 "In6.Cu" signal "IN3")
		(16 "In7.Cu" signal "GND3")
		(18 "In8.Cu" signal "VCC")
		(20 "In9.Cu" signal "VCC1")
		(22 "In10.Cu" signal "GND4")
		(24 "In11.Cu" signal "IN4")
		(26 "In12.Cu" signal "GND5")
		(28 "In13.Cu" signal "IN5")
		(30 "In14.Cu" signal "GND6")
		(32 "In15.Cu" signal "IN6")
		(34 "In16.Cu" signal "GND7")
		(2 "B.Cu" signal "BOTTOM")
		(9 "F.Adhes" user "F.Adhesive")
		(11 "B.Adhes" user "B.Adhesive")
		(13 "F.Paste" user "Package Geometry/Pastemask Top")
		(15 "B.Paste" user "Package Geometry/Pastemask Bottom")
		(5 "F.SilkS" user "Ref Des/Silkscreen Top")
		(7 "B.SilkS" user "Ref Des/Silkscreen Bottom")
		(1 "F.Mask" user "Board Geometry/Soldermask Top")
		(3 "B.Mask" user "Board Geometry/Soldermask Bottom")
		(17 "Dwgs.User" user "User.Drawings")
		(19 "Cmts.User" user "User.Comments")
		(21 "Eco1.User" user "User.Eco1")
		(23 "Eco2.User" user "User.Eco2")
		(25 "Edge.Cuts" user "Board Geometry/Outline")
		(27 "Margin" user)
		(31 "F.CrtYd" user "Package Geometry/Place Bound Top")
		(29 "B.CrtYd" user "Package Geometry/Place Bound Bottom")
		(35 "F.Fab" user "Ref Des/Assembly Top")
		(33 "B.Fab" user "Ref Des/Assembly Bottom")
	)
	(footprint ""
		(layer "F.Cu")
		(at 455.617834 -93.437964)
		(property "Reference" "R3231"
			(at 0 0 0)
			(layer "F.SilkS")
			(hide yes)
			(effects
				(font
					(size 1.27 1.27)
				)
			)
		)
		(property "Value" ""
			(at 0 0 0)
			(layer "F.Fab")
			(effects
				(font
					(size 1.27 1.27)
				)
			)
		)
		(duplicate_pad_numbers_are_jumpers no)
		(fp_line
			(start -0.7874 -0.4064)
			(end 0.7874 -0.4064)
			(stroke
				(width 0.1524)
				(type default)
			)
			(layer "F.SilkS")
		)
		(fp_line
			(start -0.7874 0.4064)
			(end -0.7874 -0.4064)
			(stroke
				(width 0.1524)
				(type default)
			)
			(layer "F.SilkS")
		)
		(fp_line
			(start 0.7874 -0.4064)
			(end 0.7874 0.4064)
			(stroke
				(width 0.1524)
				(type default)
			)
			(layer "F.SilkS")
		)
		(fp_line
			(start 0.7874 0.4064)
			(end -0.7874 0.4064)
			(stroke
				(width 0.1524)
				(type default)
			)
			(layer "F.SilkS")
		)
		(fp_line
			(start -0.67945 -0.305054)
			(end -0.12065 -0.305054)
			(stroke
				(width 0.1)
				(type default)
			)
			(layer "F.Fab")
		)
		(fp_line
			(start -0.67945 0.3048)
			(end -0.67945 -0.305054)
			(stroke
				(width 0.1)
				(type default)
			)
			(layer "F.Fab")
		)
		(fp_line
			(start -0.12065 -0.305054)
			(end -0.12065 -0.2794)
			(stroke
				(width 0.1)
				(type default)
			)
			(layer "F.Fab")
		)
		(fp_line
			(start -0.12065 -0.2794)
			(end 0.12065 -0.2794)
			(stroke
				(width 0.1)
				(type default)
			)
			(layer "F.Fab")
		)
		(fp_line
			(start -0.12065 0.2794)
			(end -0.12065 0.3048)
			(stroke
				(width 0.1)
				(type default)
			)
			(layer "F.Fab")
		)
		(fp_line
			(start -0.12065 0.3048)
			(end -0.67945 0.3048)
			(stroke
				(width 0.1)
				(type default)
			)
			(layer "F.Fab")
		)
		(fp_line
			(start 0.120396 0.2794)
			(end -0.12065 0.2794)
			(stroke
				(width 0.1)
				(type default)
			)
			(layer "F.Fab")
		)
		(fp_line
			(start 0.120396 0.3048)
			(end 0.120396 0.2794)
			(stroke
				(width 0.1)
				(type default)
			)
			(layer "F.Fab")
		)
		(fp_line
			(start 0.12065 -0.3048)
			(end 0.67945 -0.3048)
			(stroke
				(width 0.1)
				(type default)
			)
			(layer "F.Fab")
		)
		(fp_line
			(start 0.12065 -0.2794)
			(end 0.12065 -0.3048)
			(stroke
				(width 0.1)
				(type default)
			)
			(layer "F.Fab")
		)
		(fp_line
			(start 0.67945 -0.3048)
			(end 0.67945 0.3048)
			(stroke
				(width 0.1)
				(type default)
			)
			(layer "F.Fab")
		)
		(fp_line
			(start 0.67945 0.3048)
			(end 0.120396 0.3048)
			(stroke
				(width 0.1)
				(type default)
			)
			(layer "F.Fab")
		)
		(pad "1" smd circle
			(at -0.40005 0)
			(size 0 0)
			(layers "F.Cu" "F.Mask" "F.Paste")
			(net "OCP_SFF_AUX_PWR_EN")
		)
		(pad "2" smd circle
			(at 0.40005 0)
			(size 0 0)
			(layers "F.Cu" "F.Mask" "F.Paste")
			(net "OCP_SFF_AUX_PWR_EN_R2")
		)
	)
	(footprint ""
		(layer "F.Cu")
		(at 151.254206 -191.35471 -90)
		(property "Reference" "R3200"
			(at 0 0 270)
			(layer "F.SilkS")
			(hide yes)
			(effects
				(font
					(size 1.27 1.27)
				)
			)
		)
		(property "Value" ""
			(at 0 0 270)
			(layer "F.Fab")
			(effects
				(font
					(size 1.27 1.27)
				)
			)
		)
		(duplicate_pad_numbers_are_jumpers no)
		(fp_line
			(start -0.7874 0.4064)
			(end -0.7874 0.073406)
			(stroke
				(width 0.1524)
				(type default)
			)
			(layer "F.SilkS")
		)
		(fp_line
			(start 0.7874 0.4064)
			(end -0.7874 0.4064)
			(stroke
				(width 0.1524)
				(type default)
			)
			(layer "F.SilkS")
		)
		(fp_line
			(start 0.7874 -0.053594)
			(end 0.7874 0.4064)
			(stroke
				(width 0.1524)
				(type default)
			)
			(layer "F.SilkS")
		)
		(fp_line
			(start -0.41529 -0.4064)
			(end 0.42291 -0.4064)
			(stroke
				(width 0.1524)
				(type default)
			)
			(layer "F.SilkS")
		)
		(fp_line
			(start -0.67945 0.3048)
			(end -0.67945 -0.305054)
			(stroke
				(width 0.1)
				(type default)
			)
			(layer "F.Fab")
		)
		(fp_line
			(start -0.12065 0.3048)
			(end -0.67945 0.3048)
			(stroke
				(width 0.1)
				(type default)
			)
			(layer "F.Fab")
		)
		(fp_line
			(start 0.120396 0.3048)
			(end 0.120396 0.2794)
			(stroke
				(width 0.1)
				(type default)
			)
			(layer "F.Fab")
		)
		(fp_line
			(start 0.67945 0.3048)
			(end 0.120396 0.3048)
			(stroke
				(width 0.1)
				(type default)
			)
			(layer "F.Fab")
		)
		(fp_line
			(start -0.12065 0.2794)
			(end -0.12065 0.3048)
			(stroke
				(width 0.1)
				(type default)
			)
			(layer "F.Fab")
		)
		(fp_line
			(start 0.120396 0.2794)
			(end -0.12065 0.2794)
			(stroke
				(width 0.1)
				(type default)
			)
			(layer "F.Fab")
		)
		(fp_line
			(start -0.12065 -0.2794)
			(end 0.12065 -0.2794)
			(stroke
				(width 0.1)
				(type default)
			)
			(layer "F.Fab")
		)
		(fp_line
			(start 0.12065 -0.2794)
			(end 0.12065 -0.3048)
			(stroke
				(width 0.1)
				(type default)
			)
			(layer "F.Fab")
		)
		(fp_line
			(start 0.12065 -0.3048)
			(end 0.67945 -0.3048)
			(stroke
				(width 0.1)
				(type default)
			)
			(layer "F.Fab")
		)
		(fp_line
			(start 0.67945 -0.3048)
			(end 0.67945 0.3048)
			(stroke
				(width 0.1)
				(type default)
			)
			(layer "F.Fab")
		)
		(fp_line
			(start -0.67945 -0.305054)
			(end -0.12065 -0.305054)
			(stroke
				(width 0.1)
				(type default)
			)
			(layer "F.Fab")
		)
		(fp_line
			(start -0.12065 -0.305054)
			(end -0.12065 -0.2794)
			(stroke
				(width 0.1)
				(type default)
			)
			(layer "F.Fab")
		)
		(pad "1" smd circle
			(at -0.40005 0 270)
			(size 0 0)
			(layers "F.Cu" "F.Mask" "F.Paste")
			(net "CLK_100M_CPU1_CLK05_R_DP")
		)
		(pad "2" smd circle
			(at 0.40005 0 270)
			(size 0 0)
			(layers "F.Cu" "F.Mask" "F.Paste")
			(net "CLK_100M_CPU1_CLK05_DP")
		)
	)
)
